# SCM (Grand Teton) — schematic netlist excerpt (pin names and nets, part order shuffled) for the footprints in the layout excerpt that follows; sources: Cadence DE-HDL packaged netlist, KiCad conversion of 12092022_DA0F0TMDCD0_F0T_Management_Board_D_brd_V3_OCP.brd

R888  Q_RES  1K 1% EMPTY  pkg 0402LF  page 22 : A = P3V3_AUX ; B = RST_BMC_SELF_HW
PR241  Q_RES  10K 1% CHIP  pkg 0402LF  page 51 : A = P5V_AUX_VCC ; B = PWRGD_P5V_AUX_R

(kicad_pcb
	(version 20260206)
	(generator "pcbnew")
	(generator_version "10.0")
	(general
		(thickness 1.6)
		(legacy_teardrops no)
	)
	(paper "A4")
	(title_block
		(title "12092022_DA0F0TMDCD0_F0T_Management_Board_D_brd_V3_OCP.brd")
		(comment 1 "Grand Teton / footprints 489-490 of 1440")
	)
	(layers
		(0 "F.Cu" signal "TOP")
		(4 "In1.Cu" signal "GND")
		(6 "In2.Cu" signal "IN1")
		(8 "In3.Cu" signal "GND1")
		(10 "In4.Cu" signal "IN2")
		(12 "In5.Cu" signal "VCC")
		(14 "In6.Cu" signal "VCC1")
		(16 "In7.Cu" signal "IN3")
		(18 "In8.Cu" signal "GND2")
		(20 "In9.Cu" signal "IN4")
		(22 "In10.Cu" signal "GND3")
		(2 "B.Cu" signal "BOTTOM")
		(9 "F.Adhes" user "F.Adhesive")
		(11 "B.Adhes" user "B.Adhesive")
		(13 "F.Paste" user "Package Geometry/Pastemask Top")
		(15 "B.Paste" user "Package Geometry/Pastemask Bottom")
		(5 "F.SilkS" user "Ref Des/Silkscreen Top")
		(7 "B.SilkS" user "Ref Des/Silkscreen Bottom")
		(1 "F.Mask" user "Board Geometry/Soldermask Top")
		(3 "B.Mask" user "Board Geometry/Soldermask Bottom")
		(17 "Dwgs.User" user "User.Drawings")
		(19 "Cmts.User" user "User.Comments")
		(21 "Eco1.User" user "User.Eco1")
		(23 "Eco2.User" user "User.Eco2")
		(25 "Edge.Cuts" user "Board Geometry/Outline")
		(27 "Margin" user)
		(31 "F.CrtYd" user "Package Geometry/Place Bound Top")
		(29 "B.CrtYd" user "Package Geometry/Place Bound Bottom")
		(35 "F.Fab" user "Ref Des/Assembly Top")
		(33 "B.Fab" user "Ref Des/Assembly Bottom")
	)
	(footprint ""
		(layer "F.Cu")
		(at 12.319 -91.44 180)
		(property "Reference" "R888"
			(at 0 0 180)
			(layer "F.SilkS")
			(hide yes)
			(effects
				(font
					(size 1.27 1.27)
				)
			)
		)
		(property "Value" ""
			(at 0 0 180)
			(layer "F.Fab")
			(effects
				(font
					(size 1.27 1.27)
				)
			)
		)
		(duplicate_pad_numbers_are_jumpers no)
		(fp_line
			(start 0.7874 0.4064)
			(end -0.7874 0.4064)
			(stroke
				(width 0.1524)
				(type default)
			)
			(layer "F.SilkS")
		)
		(fp_line
			(start 0.7874 -0.4064)
			(end 0.7874 0.4064)
			(stroke
				(width 0.1524)
				(type default)
			)
			(layer "F.SilkS")
		)
		(fp_line
			(start -0.7874 0.4064)
			(end -0.7874 -0.4064)
			(stroke
				(width 0.1524)
				(type default)
			)
			(layer "F.SilkS")
		)
		(fp_line
			(start -0.7874 -0.4064)
			(end 0.7874 -0.4064)
			(stroke
				(width 0.1524)
				(type default)
			)
			(layer "F.SilkS")
		)
		(fp_line
			(start 0.67945 0.3048)
			(end 0.120396 0.3048)
			(stroke
				(width 0.1)
				(type default)
			)
			(layer "F.Fab")
		)
		(fp_line
			(start 0.67945 -0.3048)
			(end 0.67945 0.3048)
			(stroke
				(width 0.1)
				(type default)
			)
			(layer "F.Fab")
		)
		(fp_line
			(start 0.12065 -0.2794)
			(end 0.12065 -0.3048)
			(stroke
				(width 0.1)
				(type default)
			)
			(layer "F.Fab")
		)
		(fp_line
			(start 0.12065 -0.3048)
			(end 0.67945 -0.3048)
			(stroke
				(width 0.1)
				(type default)
			)
			(layer "F.Fab")
		)
		(fp_line
			(start 0.120396 0.3048)
			(end 0.120396 0.2794)
			(stroke
				(width 0.1)
				(type default)
			)
			(layer "F.Fab")
		)
		(fp_line
			(start 0.120396 0.2794)
			(end -0.12065 0.2794)
			(stroke
				(width 0.1)
				(type default)
			)
			(layer "F.Fab")
		)
		(fp_line
			(start -0.12065 0.3048)
			(end -0.67945 0.3048)
			(stroke
				(width 0.1)
				(type default)
			)
			(layer "F.Fab")
		)
		(fp_line
			(start -0.12065 0.2794)
			(end -0.12065 0.3048)
			(stroke
				(width 0.1)
				(type default)
			)
			(layer "F.Fab")
		)
		(fp_line
			(start -0.12065 -0.2794)
			(end 0.12065 -0.2794)
			(stroke
				(width 0.1)
				(type default)
			)
			(layer "F.Fab")
		)
		(fp_line
			(start -0.12065 -0.305054)
			(end -0.12065 -0.2794)
			(stroke
				(width 0.1)
				(type default)
			)
			(layer "F.Fab")
		)
		(fp_line
			(start -0.67945 0.3048)
			(end -0.67945 -0.305054)
			(stroke
				(width 0.1)
				(type default)
			)
			(layer "F.Fab")
		)
		(fp_line
			(start -0.67945 -0.305054)
			(end -0.12065 -0.305054)
			(stroke
				(width 0.1)
				(type default)
			)
			(layer "F.Fab")
		)
		(pad "1" smd rect
			(at -0.40005 0)
			(size 0.4572 0.508)
			(layers "F.Cu" "F.Mask" "F.Paste")
			(net "P3V3_AUX")
		)
		(pad "2" smd rect
			(at 0.40005 0)
			(size 0.4572 0.508)
			(layers "F.Cu" "F.Mask" "F.Paste")
			(net "RST_BMC_SELF_HW")
		)
	)
	(footprint ""
		(layer "F.Cu")
		(at 11.171936 -54.538372 180)
		(property "Reference" "PR241"
			(at 0 0 180)
			(layer "F.SilkS")
			(hide yes)
			(effects
				(font
					(size 1.27 1.27)
				)
			)
		)
		(property "Value" ""
			(at 0 0 180)
			(layer "F.Fab")
			(effects
				(font
					(size 1.27 1.27)
				)
			)
		)
		(duplicate_pad_numbers_are_jumpers no)
		(fp_line
			(start 0.7874 0.4064)
			(end -0.7874 0.4064)
			(stroke
				(width 0.1524)
				(type default)
			)
			(layer "F.SilkS")
		)
		(fp_line
			(start 0.7874 -0.4064)
			(end 0.7874 0.4064)
			(stroke
				(width 0.1524)
				(type default)
			)
			(layer "F.SilkS")
		)
		(fp_line
			(start -0.7874 0.4064)
			(end -0.7874 -0.4064)
			(stroke
				(width 0.1524)
				(type default)
			)
			(layer "F.SilkS")
		)
		(fp_line
			(start -0.7874 -0.4064)
			(end 0.7874 -0.4064)
			(stroke
				(width 0.1524)
				(type default)
			)
			(layer "F.SilkS")
		)
		(fp_line
			(start 0.67945 0.3048)
			(end 0.120396 0.3048)
			(stroke
				(width 0.1)
				(type default)
			)
			(layer "F.Fab")
		)
		(fp_line
			(start 0.67945 -0.3048)
			(end 0.67945 0.3048)
			(stroke
				(width 0.1)
				(type default)
			)
			(layer "F.Fab")
		)
		(fp_line
			(start 0.12065 -0.2794)
			(end 0.12065 -0.3048)
			(stroke
				(width 0.1)
				(type default)
			)
			(layer "F.Fab")
		)
		(fp_line
			(start 0.12065 -0.3048)
			(end 0.67945 -0.3048)
			(stroke
				(width 0.1)
				(type default)
			)
			(layer "F.Fab")
		)
		(fp_line
			(start 0.120396 0.3048)
			(end 0.120396 0.2794)
			(stroke
				(width 0.1)
				(type default)
			)
			(layer "F.Fab")
		)
		(fp_line
			(start 0.120396 0.2794)
			(end -0.12065 0.2794)
			(stroke
				(width 0.1)
				(type default)
			)
			(layer "F.Fab")
		)
		(fp_line
			(start -0.12065 0.3048)
			(end -0.67945 0.3048)
			(stroke
				(width 0.1)
				(type default)
			)
			(layer "F.Fab")
		)
		(fp_line
			(start -0.12065 0.2794)
			(end -0.12065 0.3048)
			(stroke
				(width 0.1)
				(type default)
			)
			(layer "F.Fab")
		)
		(fp_line
			(start -0.12065 -0.2794)
			(end 0.12065 -0.2794)
			(stroke
				(width 0.1)
				(type default)
			)
			(layer "F.Fab")
		)
		(fp_line
			(start -0.12065 -0.305054)
			(end -0.12065 -0.2794)
			(stroke
				(width 0.1)
				(type default)
			)
			(layer "F.Fab")
		)
		(fp_line
			(start -0.67945 0.3048)
			(end -0.67945 -0.305054)
			(stroke
				(width 0.1)
				(type default)
			)
			(layer "F.Fab")
		)
		(fp_line
			(start -0.67945 -0.305054)
			(end -0.12065 -0.305054)
			(stroke
				(width 0.1)
				(type default)
			)
			(layer "F.Fab")
		)
		(pad "1" smd circle
			(at -0.40005 0 180)
			(size 0 0)
			(layers "F.Cu" "F.Mask" "F.Paste")
			(net "P5V_AUX_VCC")
		)
		(pad "2" smd circle
			(at 0.40005 0 180)
			(size 0 0)
			(layers "F.Cu" "F.Mask" "F.Paste")
			(net "PWRGD_P5V_AUX_R")
		)
	)
)
